M48
INCH,TZ
T01C.008
T02C.01
T03C.012
T04C.01417
T05C.01456
T06C.016
T07C.02244
T08C.028
T09C.035
T10C.04
T11C.087
T12C.138
T13C.158
T14C.168
T15C.032
T16C.034
T17C.048
T18C.086
T19C.094
T20C.097
T21C.119
T22C.13
;LEADER: 12 
;HEADER: 
;CODE  : ASCII 
;FILE  : 16318-2-1-8.drl for board 16318-2.brd ... layers TOP and BOTTOM
;T01 Holesize 1. = 8.000000 Tolerance = +0.000000/-0.000000 PLATED MILS Quantity = 284
;T02 Holesize 2. = 10.000000 Tolerance = +0.000000/-0.000000 PLATED MILS Quantity = 2095
;T03 Holesize 3. = 12.000000 Tolerance = +0.000000/-0.000000 PLATED MILS Quantity = 89
;T04 Holesize 4. = 14.170000 Tolerance = +0.000000/-0.000000 PLATED MILS Quantity = 200
;T05 Holesize 5. = 14.560000 Tolerance = +0.000000/-0.000000 PLATED MILS Quantity = 72
;T06 Holesize 6. = 16.000000 Tolerance = +0.000000/-0.000000 PLATED MILS Quantity = 908
;T07 Holesize 7. = 22.440000 Tolerance = +0.000000/-0.000000 PLATED MILS Quantity = 12
;T08 Holesize 8. = 28.000000 Tolerance = +0.000000/-0.000000 PLATED MILS Quantity = 9
;T09 Holesize 9. = 35.000000 Tolerance = +0.000000/-0.000000 PLATED MILS Quantity = 9
;T10 Holesize 10. = 40.000000 Tolerance = +0.000000/-0.000000 PLATED MILS Quantity = 11
;T11 Holesize 11. = 87.000000 Tolerance = +0.000000/-0.000000 PLATED MILS Quantity = 2
;T12 Holesize 12. = 138.000000 Tolerance = +0.000000/-0.000000 PLATED MILS Quantity = 9
;T13 Holesize 13. = 158.000000 Tolerance = +0.000000/-0.000000 PLATED MILS Quantity = 2
;T14 Holesize 14. = 168.000000 Tolerance = +0.000000/-0.000000 PLATED MILS Quantity = 1
;T15 Holesize 15. = 32.000000 Tolerance = +0.000000/-0.000000 NON_PLATED MILS Quantity = 2
;T16 Holesize 16. = 34.000000 Tolerance = +0.000000/-0.000000 NON_PLATED MILS Quantity = 1
;T17 Holesize 17. = 48.000000 Tolerance = +0.000000/-0.000000 NON_PLATED MILS Quantity = 1
;T18 Holesize 18. = 86.000000 Tolerance = +0.000000/-0.000000 NON_PLATED MILS Quantity = 7
;T19 Holesize 19. = 94.000000 Tolerance = +0.000000/-0.000000 NON_PLATED MILS Quantity = 1
;T20 Holesize 20. = 97.000000 Tolerance = +0.000000/-0.000000 NON_PLATED MILS Quantity = 1
;T21 Holesize 21. = 119.000000 Tolerance = +0.000000/-0.000000 NON_PLATED MILS Quantity = 2
;T22 Holesize 22. = 130.000000 Tolerance = +0.000000/-0.000000 NON_PLATED MILS Quantity = 2
%
G90
T01
X787401Y290944
X787408Y294074
X784258Y294064
X784251Y290944
X781088Y294094
X777989Y294093
X777952Y290944
X774802
X774835Y294088
X771653Y294093
X768503Y290944
X768498Y294124
X765353Y290944
X765325Y294102
X762173Y294089
X759054Y290944
X759055Y294094
X755905Y294093
Y290944
X219800Y445700
X213874Y445226
X197243Y539371
X194094Y539370
X184645
X156300Y539371
X153149Y536221
X156299Y542521
Y545671
X159449
Y542521
Y548821
X162599
Y542519
Y545669
X165749Y548819
Y542519
Y545669
X168898Y542519
Y545669
Y548819
X172047
Y545669
X175197Y545671
Y548821
X178346Y545670
X181496Y542520
X181497Y548821
Y545671
X184646Y548821
Y545671
X184645Y542519
X190945
X194094Y548820
Y545669
Y542519
X197244Y545669
Y542520
X200393Y548819
Y545669
X203542Y548821
Y545671
X206692Y542521
Y545671
X209842Y548819
Y545669
X212992Y548819
Y545669
X212991Y542519
X216142Y548820
Y545669
X219291Y548820
X222441
X216141Y558269
Y555120
Y551970
X212992Y551969
Y555119
Y558268
X209842Y551969
Y555119
Y558268
X206692Y555120
Y558269
X200395Y555120
X197245Y555118
X197243Y551970
X194093Y555120
Y551970
X190944Y555118
X187795Y555120
X184646
X181497
Y551970
X178347
X178346Y555119
X175197Y551970
Y558268
X172048Y555120
X172047Y551970
X168898Y551969
Y558268
Y555119
X165748Y551968
Y555118
Y558268
X162598
X162597Y555118
X159449
X159448Y551968
X156297Y558267
X159449Y561417
Y567717
X162598
X162595Y564567
X162598Y561417
X165745Y564567
X165748Y567717
Y561417
X168895Y564567
X168898Y561417
Y567717
X172047Y561417
X172048Y564569
X172047Y567717
X178347Y564569
X184646Y567716
X187795
Y564567
X190945Y567716
X194094
X203543Y564568
Y561418
X206692Y567718
Y561419
Y564569
X209842Y567717
Y564567
Y561417
X212991Y567718
X212992Y564567
Y561417
X216141Y564569
Y561419
Y567718
X219293Y567717
X216141Y577165
Y574016
X212991Y577165
Y574016
X209841Y577165
Y574016
X206692
X203543Y574017
X200394Y574016
Y570866
X190945
X190944Y574016
X190945Y577165
X187795
Y570866
Y574016
X184646Y577165
Y574016
Y570866
X178347Y570868
Y574018
X178344Y577166
X175298Y577266
X172000Y577150
X172047Y570866
X168898Y577165
Y570866
X165748
X162598
Y577165
X159449Y570866
Y577165
X156299Y570866
Y577165
Y580315
Y586614
X159448Y589764
X159449Y580315
Y586614
X162598
Y589764
Y583464
Y580315
X165748Y586614
Y589764
Y580315
Y583464
X168898Y586614
Y583464
Y589764
Y580315
X172048Y589764
X175197
X178347
X178346Y586615
X181497Y589764
Y586614
X184645Y589764
X187794Y586614
X190944
Y589764
X194093Y586614
Y589764
X197244Y586615
X197243Y589764
X200393Y586614
Y589764
X203542Y586614
Y580315
Y589764
X206692Y583465
Y580315
Y589763
Y586614
X209841Y580315
X209842Y586613
Y589763
Y583464
X212991Y583465
X212992Y586614
Y580315
Y589764
X216141Y586614
Y589762
Y583465
Y580315
Y599212
X212991
X212993Y592912
X209841Y596063
Y592913
Y599212
X206692Y592913
Y596063
Y599213
X203542Y592913
Y599213
Y596063
X200393Y592913
Y596063
X197243Y592913
X194093
X194094Y599213
X194093Y596063
X190945Y599213
X190944Y592913
Y596063
X187796Y599212
X187795Y592914
X184645Y599213
X181496Y596062
X181497Y592913
X178347Y599213
X178346Y596064
X175197Y596063
Y599213
Y592913
X172048Y596063
Y599213
Y592913
X168898Y599213
Y592913
Y596063
X165748Y599213
Y592913
Y596063
X162598Y599213
Y596063
X159448Y599213
Y596063
Y592913
X153149Y605513
X187795Y602363
X194094Y602362
X203542
X203605Y605450
X206692Y602362
X212992Y602363
X222440Y605512
T02
X30270Y48330
X29890Y54070
X38590Y55260
X26576Y457406
X31100Y458733
X34132Y521245
X34175Y526969
X29165Y532612
X29058Y538228
X29158Y543855
X28800Y549474
X28782Y555119
X33697Y560866
X37660Y566400
X38550Y617950
X50800Y667900
X47150Y665500
X50700Y664000
X40309Y660700
X59200Y582200
X42597Y571789
X53302Y567317
X53300Y560879
X52485Y555153
X52603Y549526
X52408Y543876
X52613Y538242
X53524Y532622
Y526995
Y521269
X49600Y496050
X55300Y495600
X41250Y494600
X49460Y63690
X54050Y63260
X56960Y58900
X43510Y57810
X77780Y61790
X73760Y67930
X68730
X69904Y502077
X64277Y502177
X75399Y502179
X75405Y521695
X64151
X69778
X74076Y535966
X64400Y539000
X67852Y539219
X71002
X75508Y542198
X67853Y542368
X64701Y542366
X71002Y542368
Y545518
X74151Y545516
X78276Y545566
X61100Y546700
X71002Y548668
X62276Y550493
X74498Y551757
X63456Y555041
X71002Y554967
X67853
X71002Y558117
X67853
X64701Y561266
X67853
X71002
X75066Y563235
X71002Y564396
X64701Y564416
X67853
X74152Y567565
X71002
X64701Y567566
X67853Y570715
X64701Y570716
X75197Y572437
X67853Y573865
Y577015
X71002Y577013
X74152
Y580163
Y583312
X67852Y583313
X64703Y586463
X67852
X64884Y650984
X76100Y697100
X71850Y698900
X87683Y698924
X84600Y688000
X85500Y628500
X98200Y616900
X93053Y606734
X97800Y606300
X93051Y587466
X89901
X86750Y586463
Y583313
X96570Y581730
X93048Y580164
X83601
X86750Y577014
X93048
X89899
X86750Y573864
X83600Y573865
X89899Y573864
X93049
X83600Y567565
X86750
X89899
X83600Y564415
X86750
X89899
Y561265
X86750
X83600
X89899Y558115
X86750
X94720Y557158
X86750Y554965
X83600Y551817
X86750Y551815
X81276Y548766
X94473Y547093
X89899Y545518
X83600
X86750
Y542368
X93744Y542019
X86750Y539218
X83600Y539219
X89899Y539218
X92600Y535623
X96371Y534124
X86659Y521695
X81032
X92286
X97913
X97926Y502300
X86699
X81094Y502166
X97637Y492891
X84610Y64470
X89070Y62600
X98770Y60860
X97600Y54810
X108300Y435900
X114390Y453185
X118108Y453159
X102250Y455000
X116500Y477000
X105920Y477098
X114070Y481948
X114500Y490000
X101800Y493000
X117200Y495200
X107100Y497300
X102700Y507100
X119400Y511500
X105350Y511850
X118900Y522000
X117200Y546300
X106272Y547370
X119605Y548705
X117400Y567650
X108371Y577258
X101500Y597000
X105600
X105400Y601300
X117050Y602000
X105600Y605900
X101400Y606300
X119600Y606700
X116023Y607423
X104600Y609900
X116200Y611600
X104600Y614000
X119400Y614100
X116400Y616900
X104500Y618800
X116500Y621000
X119000Y633200
X118500Y638100
X107100Y679600
X106635Y701465
X111300Y705500
X106879Y707245
X119849Y709715
X106355Y710745
X125376Y701124
X125100Y656700
X136100Y656300
X130800Y656100
X120500Y651800
X130500Y638600
X134700
X138500Y637900
X129903Y634500
X129800Y630700
X122000Y628700
X137210Y622030
X130630Y620900
X134030Y620760
X122750Y616950
X123500Y613100
X134650Y612900
X127401Y606930
X130800Y606700
X123370
X126347Y569556
X130607Y569636
X122600Y557480
X126337Y554085
X130311Y546700
X127300Y543200
X133554Y537374
X136990Y535235
X123200Y534600
X123300Y530300
X133800Y528500
X138900Y525999
X135012Y510200
X132774Y497000
X132100Y493000
X138000Y485900
X133152Y484074
X137050Y476346
X121826Y453156
X128968Y452741
X125353Y452385
X136021Y451394
X132109Y451199
X127812Y445066
X146301Y460200
X157496Y461248
X146293Y464338
X146263Y468562
X146293Y472738
X146193Y476938
X158000Y480700
X146143Y481057
X146216Y486045
X154500Y487000
X144500Y489500
X146500Y492500
X150500Y493000
X158100
X158290Y502380
X146300Y502600
X155540Y506510
X159480Y506590
X141980Y508590
X146112Y509412
X158400Y513600
X155001Y513707
X148527Y519491
X145400Y524046
X150162Y525937
X143500Y529000
X149242Y531080
X152584Y532922
X149419Y535654
X152415Y540014
X148409Y575672
Y579353
X144876Y587173
Y590854
X144750Y606350
X142447Y611714
X141971Y624700
X151550Y629800
X146800Y629900
X157200Y634200
X152700Y640800
X145900Y641300
X140700Y657700
X144800Y657900
X151949Y691715
X159519Y694455
X148249Y695765
X151130Y703440
X150849Y710215
X162100Y711215
X163260Y706988
X175233Y704382
X163349Y702715
X169070Y696220
X173000Y640400
X169000Y640300
X164800Y640200
X161000Y634300
X178140Y630330
X177300Y626800
X166600Y617850
X166690Y615060
X170940Y614400
X171020Y611020
X160420Y610170
X163200Y610070
X168390Y532060
X175100Y529100
X175805Y524073
X165900Y524100
X174700Y513900
X170700Y513600
X178869Y513593
X166600Y513600
Y509800
X178869Y509793
X170700Y509800
X170900Y500000
X179000Y499800
X174900
X166700
X170870Y492270
X176800Y492200
X170838Y481762
X175100Y477000
X176100Y473200
X172100Y467300
X172370Y463798
X176000Y460200
X172200Y460100
X193686Y459799
X186602Y459767
X190278Y459865
X197085Y459899
X186735Y463748
X187000Y468000
X186600Y477700
X190950Y482100
X196200Y482600
X196243Y486782
X183300Y493100
X195300Y498900
X187000Y499500
X183100Y499800
X182300Y509600
X191418Y509981
X195379Y510158
X187167Y513167
X191100Y513367
X182874Y513591
X195149Y513751
X191725Y523074
X182874Y523590
X191100Y526000
X184780Y526990
X199400Y529400
X195300
X191200
X184830Y529960
X191370Y608190
X191110Y611050
X181176Y627600
X187900Y628500
X192960Y628510
X199400Y628646
X184050Y629500
X196249Y630091
X189500Y639700
X193610Y640040
X180700Y640460
X184967Y643983
X194490Y645390
X195900Y649350
X199600Y650100
X189000Y659900
X196900Y661350
X193500Y663000
X190200Y671000
X187500Y673100
X181300Y679100
X191766Y679920
X196855Y698355
X185100Y705600
X184800Y709300
X217638Y695562
X206700Y695400
X214270Y695095
X200400Y694700
X206300Y661100
X202800Y660900
X216600Y658400
X218200Y651400
X203400Y649600
X219200Y647200
X215606Y645806
X207900Y645600
X211706Y645349
X204150Y645180
X200610Y639611
X218800Y635600
X200560Y635100
X213800Y631200
X208700Y625149
X204642Y621140
X212900Y619201
X204800Y617440
X209093Y615849
X200879Y614739
X212308Y605949
X211500Y529400
X203610Y529397
X214900Y529400
X208000Y529300
X211700Y513500
X203500
X206180Y509524
X203307Y506400
X207500Y503000
X200100Y491700
X208370Y491570
X205447Y487762
X211196
X213359Y480489
X209800Y478500
X213100Y476300
Y472900
X205516Y467968
X209256Y467946
X239300Y443800
X236100Y445100
X224500Y445600
X232200
X230700Y486658
X228700Y490717
X234700Y490900
X222600Y503500
X238400Y511300
X231800Y512100
X227500Y512200
X223600Y512400
X220100Y513400
X225914Y523051
X228150Y525750
X223900Y531200
X232400Y533200
X222500Y536161
X228800Y542100
X228100Y545500
X233036Y550942
X228313Y552169
X233607Y557671
X231434Y562844
X234943Y565199
X231000Y571900
X234800Y572000
X231200Y576800
X230900Y581600
X234300Y582300
X237100Y590000
X229800Y593200
X233258Y595693
X234205Y598743
X228149Y600094
X229796Y610104
X232130Y612950
X221238Y620524
X234000Y629576
X225900Y630700
X221900Y630800
X229500Y631500
X229137Y634881
X229063Y638560
X236000Y647400
X222950Y647900
X230900Y649100
X226471Y649129
X231500Y659100
X237509Y674915
X239400Y677900
X235100Y679921
X235000Y692900
X221575Y695400
X254648Y745463
X258423Y711343
X253196Y706062
X242000Y693400
X254800Y689400
X255200Y680950
X255050Y675750
X247825Y670375
X247725Y656375
X242000Y656400
X245100Y647200
X259777Y638873
X245300Y635700
X255228Y631071
X255648Y626127
X255733Y622329
X255570Y616631
X258962Y616384
X256001Y612347
X258550Y610096
X248450Y609900
X251900Y609600
X258550Y606527
X242710Y604620
X254199Y603443
X258869Y603050
X246500Y601500
X251338Y601506
X251314Y598106
X243322Y597509
X254600Y597100
X247400Y589600
X254300Y586500
X257700Y586400
X247100Y582400
X257851Y580080
X254500Y579500
X257600Y576500
X254500Y575070
X257000Y571700
X259100Y567706
X254600Y567700
X254530Y564300
X257891Y563786
X254905Y555761
X258528Y555161
X251446Y553754
X246611Y551511
X257000Y548400
X252593Y547650
X245743Y546963
X248900Y545700
X257300Y537500
X246484Y537139
X244900Y527300
X249050Y527150
X242500Y523500
X246000Y516670
X258100Y516400
X254500Y509600
X258381Y509498
X249640Y495080
X254900Y453900
X259000
X250500Y451300
X244700Y451200
X247900Y445300
X243000Y443800
X251700Y443600
X260600Y442600
X268900Y445150
X275100Y460300
X272000Y461800
X268350Y461950
X278400Y463300
X275500Y466200
X275400Y470300
X275200Y474500
X267800Y479900
X277603Y479948
X275700Y490300
X276634Y498311
X265274Y509512
X265148Y524595
X261200Y525400
X264333Y528926
X279664Y535473
X267957Y537304
X271357Y537253
X277441Y539882
X260741Y542700
X270021Y549394
X263216Y554697
X270145Y557526
X260731Y561264
X273500Y567400
X269900Y567619
X261100Y571600
X261500Y576400
X274623Y578896
X261600Y580000
X276839Y582309
X261308Y583388
X262000Y586900
X277048Y590470
X273400Y590902
X261900Y591300
X270000Y602400
X275470Y608480
X266571Y608619
X270400Y622870
X266847Y626253
X273714Y629870
X266571Y630071
X278546Y633450
X266857Y634343
X274800Y635000
X264040Y648370
X272200Y648550
X278443Y648857
X265000Y662574
X268384Y662909
X270900Y667200
X275300Y668749
X266400Y675349
X276100Y677700
X266200Y679400
X279400Y686400
X266300Y692574
X276800Y697925
X269200Y699600
X264700Y700000
X261248Y700086
X278769Y700697
X267880Y704920
X262634Y711233
X272050Y711810
X262323Y716917
X268520Y719420
X263700Y723500
X278553Y740020
X298570Y743670
X287620Y737300
X291700Y737000
X290000Y727000
X280646Y717540
X281500Y712200
X281400Y708200
X282300Y700100
X294804Y695204
X293300Y679700
X289700Y678830
X281000Y678000
X288700Y667900
X296800Y665081
X281900Y640900
X290500Y640600
X290300Y636900
X287200Y632600
X290900Y630900
X294500Y630600
X298100Y630650
X286700Y622190
X284495Y613130
X296835Y591015
X281610Y590260
X281490Y586862
X292850Y586100
X282000Y583500
X295824Y578108
X291800Y576708
X291000Y570810
X288309Y566467
X298000Y561000
X294107Y560762
X280646Y557150
X293271Y557248
X298514Y550184
X285800Y549394
X285982Y542502
X285912Y538750
X280100Y532100
X286195Y530579
X293087Y530571
X293793Y521556
X298335Y521458
X297400Y517981
X286797Y516522
X292100Y516000
X299448Y511300
X298907Y505851
X280939Y504705
X282403Y474500
X282400Y470200
X286700Y457500
X281200Y453500
X299107Y177740
X295841Y176793
X295462Y173414
X311715Y20397
X310353Y62159
X305700Y197600
X305703Y202165
X306407Y206057
X305498Y213824
X305782Y217274
Y220674
X305682Y224074
X305382Y227474
X305782Y230874
X305882Y234274
X305772Y237673
X305781Y241076
X305454Y244461
X306446Y247874
X305373Y251101
X306412Y254339
X304231Y261048
Y265048
Y268548
Y272548
X307567Y273592
Y277592
Y281092
Y285092
X304267Y286192
Y290192
Y293692
Y297692
X307567Y298792
Y302792
Y306292
Y310292
X304267Y311392
Y315392
Y318892
Y322892
X307567Y324092
Y328092
Y331592
Y335592
X304267Y336592
Y340592
Y344092
Y348092
X307567Y349192
Y353192
Y356692
Y360692
X304267Y361792
Y365792
Y369292
Y373292
X303680Y380972
X316900Y384100
X319679Y387121
X314000Y390500
X302307Y505799
X307364Y505750
X314400
X304800Y512800
X308687Y519193
X310292Y532128
X310350Y538293
X300476Y546907
X318736Y549697
X303520Y550085
X319430Y557486
X319529Y562413
X319252Y566509
X303500Y582200
X316680Y583527
X303100Y587000
X308200Y593153
X306100Y599500
X302459Y599531
X317689Y599833
X306231Y602898
X302180Y603084
X317600Y603300
X305470Y623734
X304400Y665100
X304700Y668500
X300100Y670300
X319600Y670450
X311600Y670354
X316000Y671850
X318400Y678400
X316465Y716063
X313873Y735907
X314100Y739300
X306470Y743570
X327250Y701500
X327162Y696776
X338669Y691580
X339804Y679030
X325900Y678500
X321800
X336200Y677000
X335750Y664700
X339266Y658409
X331718Y655832
X329100Y650700
X335100Y650600
X325300Y648700
X334700Y644500
X330400Y644300
X338100Y635800
X339081Y628173
X339847Y620281
X339751Y616882
Y613185
X339822Y609785
X331655Y603405
X338733Y603039
X335036
X337899Y587874
X331700Y587896
X334900Y586100
X327110Y583660
X337300Y583000
X325475Y572818
X329840Y572710
X320954Y572631
X328580Y568120
X324200Y565300
X323659Y557310
X330729Y557268
X327059Y557247
X333512Y553888
X330860Y551744
X325687Y551368
X336367Y549943
X328771Y549035
X332808Y547575
X325774Y547428
X337346Y545100
X332834Y543993
X325447Y536109
X333800Y534830
X337550Y534619
X322843Y533254
X333847Y531105
X322889Y529380
X333922Y527323
X321208Y519411
X329035Y519325
X325136Y519316
X332821Y515415
X328200Y511600
X334650Y508900
X331200
X325400Y505800
X321976Y505750
X336600Y504500
X336800Y499967
X333850Y458400
X327159Y435201
X323759Y435145
X338800Y435100
X335982Y390874
X334000Y382700
X335800Y379800
X328182Y379518
X321202Y376887
X328182Y375518
Y372018
Y368018
X321432Y367279
X334582Y366974
Y362974
Y359474
Y355474
X321432Y354681
X328182Y354371
Y350371
Y346871
Y342871
X321432Y342082
X334582Y341771
Y337771
Y334271
Y330271
X321432Y329484
X328182Y329174
Y325174
Y321674
Y317674
X321432Y316885
X334582Y316574
Y312574
Y309074
Y305074
X321882Y304374
X328182Y303977
Y299977
Y296477
Y292477
X321882Y291874
X334582Y291284
X337808Y288709
X334582Y287284
Y283784
Y279784
X321432Y279090
X328913Y274414
X334017Y272000
X321281Y266486
X335060Y262516
X334998Y259033
Y255520
X321197Y254433
X321600Y250000
X321700Y246000
X335082Y231574
X322426Y231331
Y227531
X335000Y226992
X322426Y223731
X322301Y220009
X321782Y215974
X323582Y179064
X338743Y122894
X339232Y113960
X326553Y34687
X354798Y22452
X341484Y110328
X340297Y117548
X342539Y120370
X349206Y129948
X348082Y186224
X349072Y189774
Y193574
X359882Y203458
X341882Y251064
X347482Y254774
X342885Y276301
X342958Y279701
X346600Y375000
X345582Y380874
X344732Y386874
Y390274
Y393882
X342700Y435200
X346500
X357900Y450800
X350491Y453809
X355400Y453800
X350400Y459000
Y462400
X358800Y478000
X357450Y491450
X357700Y499000
X344500Y500300
X349088Y500296
X355300Y502700
X359100Y503200
X344400Y505400
X355300Y506100
X344700Y509000
X355300Y510100
X340961Y511600
X355300Y513500
X341500Y520400
X353300Y521400
X345497Y527644
X341740Y535800
X351600Y540600
X341493Y541250
X341316Y545000
X344163Y553395
X345259Y557566
X348300Y565400
X343840Y566440
X342440Y571770
X346590Y572090
X350278Y572306
X352279Y580294
X349000Y581360
X355012Y582324
X348314Y585614
X346303Y591947
X359258Y596820
X352720Y600970
X342133Y603008
X348000Y612661
X352400Y626102
X344564Y628104
X343797Y631417
X340100
X359036Y635900
X348600Y643500
X350500Y647600
X355000Y652160
X354102Y660666
X341934Y662794
X343200Y667600
X358296Y672460
X343338Y679236
X346000Y684300
X341900Y690350
X340403Y699400
X340300Y703100
X346465Y703185
X355298Y711750
X340500
X351100Y712100
X346600Y714500
X340100Y718200
X364200Y713100
X376342Y711260
X372350Y698400
X367600Y696800
X369600Y693400
X367700Y685450
X378595Y664960
X374200Y645871
X379400Y641800
X370200Y636400
X361227Y630300
X372408Y629626
X367133Y596067
X377700Y595000
X364014Y593996
X364964Y588771
X364900Y585171
X361279Y581647
X374292Y580300
X372600Y576207
X362100Y574700
X361900Y570800
X371227Y566830
X366270Y563400
X372939Y559838
X362300Y555200
X362700Y551200
X370223Y549965
X363008Y547309
X370247Y546218
X369500Y542900
X373500Y540305
X379050Y539931
X373222Y535938
X368721Y525271
X364500Y525260
X373699Y521160
X374800Y516912
X369000Y512700
X369300Y508700
X373800Y503000
X374715Y498722
X365800Y498300
X378267Y496100
X374751Y485636
X371900Y481548
X372000Y477710
X366950Y464700
X370900
X363500
X367400Y461200
X374700Y460300
X369900Y458700
X374650Y456771
X364500Y453700
X360100Y453500
X372000Y452100
X378492Y378175
X372491Y378025
X367358Y372531
X367471Y369120
X365100Y348300
X365200Y344400
X361792Y243154
X362722Y237674
X362197Y222068
X372888Y208022
X371775Y200577
X370149Y167337
X370882Y163688
X362000Y124000
X375000Y107300
X369253Y88733
X374844Y87900
X367287Y77118
X374844Y76700
X375300Y72150
X375200Y63400
X368059Y57759
X370870Y45605
X380500Y30000
X384000
X380500Y33500
X381173Y49058
X381156Y54116
X393206Y77614
X386759Y79693
X390456
X390964Y87226
X388700Y89800
X384666Y93741
X381269Y94981
X387393Y160859
X387202Y164664
X392458Y171676
X392102Y175384
X383170Y329807
X383327Y343379
X383285Y347114
X396561Y351418
X383030Y352442
X381106Y441241
X384395Y449114
X387450Y454558
X387396Y458126
X387450Y467000
X386367Y474700
X389349Y480100
X389288Y483500
X390229Y508189
X381986Y515631
X384849Y521681
Y525499
X385600Y529107
X386723Y544565
X388641Y549747
X384950Y551876
Y555276
X399946Y558677
X384950Y560496
X399726Y562327
X383056Y563675
X393912Y568499
Y571899
X393910Y575305
X383000Y577000
X393912Y578705
X386305Y581647
X391993Y582154
X383300Y600600
X382438Y608755
X382380Y612277
X391150Y613429
X381967Y616123
X384300Y619925
X383199Y623168
X384410Y633530
X384158Y638105
X380443
X385163Y641354
X389999Y664697
X382308Y665022
X392500Y673500
X392800Y677600
X396419Y679708
Y683186
X380387Y685261
X396419Y686586
X383800Y688400
X392500Y692500
X396166Y692630
X392720Y697500
X399154Y699950
X384220Y700618
X380300Y703000
X399093Y703350
X398983Y706749
X388626Y715509
X399999Y673422
X400064Y652598
X400060Y554743
X400093Y536351
X400080Y528243
Y523903
Y519500
Y500854
Y491107
X400351Y165605
X404727Y162141
X400205Y161906
Y158209
X400212Y154732
X400430Y147190
X419662Y71426
X415211Y71263
X438600Y91033
X423340Y71621
X433400Y63373
X439302Y34040
X439554Y30429
X439549Y26339
X428001Y25269
X430800Y22200
X439200Y22100
X433600Y19900
X450454Y38147
X458972Y49634
X448520Y49979
X442800Y90934
X461736Y111300
X479147Y102165
X473172Y95508
X469901Y94047
X477400Y69300
X459950Y58000
X473151Y50052
X462625Y49881
X469058Y49156
X467300Y20000
X478500Y19775
X491270Y18877
X496430Y22890
X496700Y32100
X485674Y32924
X486568Y38006
X486114Y41700
X482693Y42200
X490050Y45900
X496035Y46435
X481800Y71200
X486400Y74700
X490100Y111300
X510408Y85779
X513909Y85849
X515500Y57900
X503814Y56676
X512806Y49494
X506970Y18693
X502830
X524950Y16120
X521200Y57600
X539346Y114333
X540179Y111036
X559900Y88400
X551500Y82400
X547100Y79900
X545300Y75600
X545200Y69000
X552540Y64530
X549550Y61900
X559600Y47600
X559200Y36265
X575550Y42800
X573600Y49750
X568430Y50010
X564500Y64100
X569300Y66274
X568000Y70000
X578400Y74500
X577100Y78600
X578900Y82500
X563268Y88872
X562160Y178600
X593064Y400910
X593229Y397308
X586155Y393023
X582219Y386612
X596077Y369579
X598964Y354128
X599682Y103715
X584550Y80750
X596300Y66950
X597950Y58950
X599422Y51662
X596489Y14110
X601311Y13521
X613480Y333710
X602075Y339970
X616900Y343000
X612300Y344300
X607100Y351200
X606626Y354723
X610300Y354800
X608600Y362600
X615150Y364200
X618600Y364375
X609240Y370337
X616428Y379533
X607800Y382362
X599998Y391270
X605400Y393400
X613000Y463000
X616160Y542700
X606600Y551100
X610200Y555400
X614000Y561250
X619400Y570451
X628160Y569095
X638660Y568043
X632800Y561600
X635970Y557600
X620160Y544793
X636963Y405999
X632180Y397968
X632220Y389694
X629239Y387969
X620100Y384100
X638360Y383805
X637353Y379591
X637000Y373856
X626772Y371336
X639318Y354003
X629900Y339300
X638603Y296320
X631069Y292512
X634830Y292095
X638453Y291949
X633400Y274600
X625250Y264250
X620750Y258050
X627200Y253550
X634450Y252100
X631550Y249850
X625926Y247530
X625550Y244150
Y240750
X632900Y238000
X625700Y235750
X633109Y234397
X632958Y231000
X628300Y230550
X636491Y217592
X633092Y217496
X629400Y217300
X620160Y203500
X619980Y197550
X629500Y187500
X634000
X630000Y169600
X634910Y169360
X638470Y164470
X634800Y147700
X630800Y147600
X644100Y199850
Y203350
X659500Y205300
X640400Y217600
X645516Y225334
X642547Y226992
X640141Y259859
X645400Y264050
X652850Y269600
X649000Y273500
X642300Y276450
X652100Y279300
X648000Y281300
X657500Y281500
X648700Y292900
X645403Y296229
X642003Y296249
X648700Y303600
X656700Y305607
X652500Y305707
X643082Y353941
X654600Y367600
X640968Y370425
X659300Y373100
X642270Y383869
X654670Y391494
X655100Y436900
X657900Y443200
X654300Y504100
X653600Y540300
X672500Y507100
X677275Y485625
X666216Y470684
X675555Y318736
X672350Y317600
X677300Y314900
X669950Y310950
X664600Y306100
X660700Y292200
X677800Y215900
X666700Y205600
X662900Y205300
X665500Y201900
X674300Y198900
X677770Y196410
X666535Y26149
X666400Y22200
X665800Y7550
X692600Y201300
X691600Y207600
X691243Y211743
X696300Y215750
X690600Y230700
X696600Y241500
X682030Y253630
X693800Y264300
X694307Y283485
X698039Y285854
X681800Y287950
X695508Y288964
X692750Y293200
X690579Y299964
X695300Y306700
X688000Y313200
X684400Y313400
X681200Y314900
X694675Y323900
X691873Y403800
X691813Y407210
X691874Y410741
X699900Y453600
X690550Y453850
X690300Y460200
X682400Y463400
X696800Y476400
X683583Y485841
X689100Y507900
X696000Y508400
X697200Y529200
X693900Y597800
X708600Y608500
X703800Y608400
X712708Y603038
X702515Y597064
X705176Y593429
X719626Y590829
X714800Y567956
X705676Y562429
X710459Y554134
X717450Y551554
X710000Y549100
X703440Y548820
X710100Y545600
X716078Y492334
X715391Y479109
X702824Y476476
X708300Y445800
X709006Y410206
X718300Y362900
X713500
X718000Y353000
X712417Y352800
X708100Y331410
X712410Y331320
X716300Y331340
X702250Y329650
X718340Y315800
X719200Y307400
X713339Y306954
X711799Y304234
X714619Y303884
X704079Y300964
X705579Y298464
X706796Y295829
X707834Y293060
X701708Y292364
X718099Y290964
X714949Y287814
X718099
X707079Y286964
X710329Y285214
X718080Y284653
X700323Y283078
X702939Y281484
X718117Y281465
X706277Y279162
X718072Y278346
X708409Y276771
X718137Y275186
X718109Y272034
Y268934
X710679Y267894
X718072Y265748
X704579Y261964
X718098Y259423
X704579Y258164
X718121Y256326
X718129Y253144
X701500Y250564
X718089Y249984
X706100Y250000
X718089Y246834
X714961Y243700
X711812
X718089Y243684
X706079Y240664
X718111Y240550
X709679Y239164
X718111Y237401
X705779Y236764
X710716Y235827
X718110Y234252
X714945Y234230
X707679Y233664
X705529Y231064
X718111Y231101
X709079Y229564
X718111Y227952
X704279Y226664
X718111Y224802
X709615Y223228
X718111Y221653
X703979Y219995
X707923Y219765
X708900Y214500
X702900Y212350
X706500Y212150
X713168Y207689
X716116Y207469
X718895Y207125
X705364Y205864
X703320Y203900
X710079Y203664
X718123Y201101
X711150Y184550
X716650
X705650
X716650Y174400
X711150Y174300
X736803Y52087
X722150Y174300
X730550Y179050
X722150Y184550
X727150
X737000Y185900
X732000
X738160Y199480
X725466Y200819
X722322Y200935
X732264Y204312
X726988
X729800Y208400
X733859Y212206
X737029Y215337
X733859Y215355
X730709
X724410
X727560
X737008Y221654
X724410
X733858
X721295Y221651
X727559Y221654
X730709
X724410Y227953
X727594Y227950
X737009Y227953
Y231103
X727559Y234252
X733859Y234253
X730710Y234254
X724410Y234252
X737009Y234253
X721260Y234252
X737009Y237400
X733859Y237403
X730710
X737009Y240552
X733859
X721261Y240551
X724410
X730710Y240553
X727559Y240551
X737008Y243700
X730710Y243702
X733858Y243700
X737008Y246849
X733858
X724410Y246850
X721261Y246851
X727560
X730710Y246852
X737008Y249999
X730710Y250002
X733858Y249999
Y253149
X737008
X724410Y253150
X730710Y253152
X721260Y253150
X727559
X730710Y256302
X737008Y256299
X733858
X727559Y259449
X724410
X721260
X724410Y265748
X737008Y265747
X733858
X721260Y265748
X727559
X730710Y265750
Y268899
X733858Y268897
X737008
X721260Y272047
X727559
X730710Y272048
X733859
X737008Y272046
X724410Y272047
X733859Y275198
X737009Y275196
X721260
X727559Y278346
X733859
X724410
X733859Y281496
X730710
X737009
X724410
Y284645
X737009Y284646
X733859
X721230Y284653
X730708Y290944
X737007
X727558
X733857
X724409
X733892Y297246
X724409Y297243
X727558
X737008Y297244
X730708Y297243
X724063Y306305
X722468Y308964
X726895Y309117
X730300Y314900
X721820Y315750
X738465Y352935
X722500Y353000
X727000
X731400Y362700
X729900Y393200
X735300Y401957
X721504Y402321
X720900Y412900
X725366Y470722
X728874Y470860
X730600Y493100
X736600Y500000
X725000Y576100
X723369Y599835
X722300Y608200
X722122Y611840
X747200Y611900
X753099Y530282
X757099Y530082
X759200Y508000
X742300Y498200
X745700Y498250
X750600Y497400
X759169Y497414
X755500Y492600
X747125Y483924
X740253Y483893
X743726Y483813
X759000Y482900
X749534Y346566
X752363Y343737
X754837Y341263
X757666Y338434
X743434Y335566
X746263Y332737
X748737Y330263
X751566Y327434
X744400Y322800
X744881Y309000
X759208Y304284
X749816Y303716
X759058Y300414
X749579Y297254
X740157Y297243
X743306
X746456
Y290944
X743306
X749605
X740157
X759073Y287810
X755898Y287804
X749593Y284670
X746457Y284646
X743308
X740158
X759070Y281514
X740159Y281496
X752756Y278346
X749606
X740159Y278345
X740158Y275197
X749607
X759031Y275209
X752757Y275197
X746457
X759031Y272060
X755882
X749581
X752731
X743283
X746457Y272047
X740158Y272046
Y268897
X746433Y265761
X749582
X743282
X740158Y265747
X755868Y265748
X752757Y265749
X759056
X743282Y259461
X759031
X755882
X749582
X752757Y259449
X746457
X740158Y256299
X743282Y253161
X759056Y253150
X749608
X755869Y253149
X746421
X740158
X752720
X740158Y249999
X759056Y246851
X752757
X755907
X749569Y246850
X743307
X740158Y246849
X746457Y246850
X740122Y243700
X749580Y240563
X755880
X752757Y240552
X759056
X743281Y240562
X740132
X746457Y240552
Y234253
X752756
X749606
X755906
X746457Y231103
X749606
X752756
X755906
X752756Y227954
X755906
X746457
X749606
X755906Y224804
X746457
X752756
X749606
X746457Y221654
X755906
X752756
X759055
X743307
X740158
X749606
X752759Y218499
X755909Y218514
X743279Y215364
X746457Y215355
X740158
X743279Y212196
X741294Y208274
X743008Y206059
X749455Y202200
X749600Y199300
X749400Y195600
X745700Y185900
X741300Y185700
X753400Y185400
X749900Y185200
X753800Y181500
X750500Y118500
X750600Y114200
X756431Y54010
X746500Y47200
X776600Y35250
X762765Y42200
X776300Y47600
X769812Y53660
X779400Y54750
X777550Y62350
X761900Y81700
X776500Y82700
X763825Y89975
X769500Y91000
X773200Y97600
X772800Y107550
X772700Y113000
X762000
X776850Y115050
X769710Y125150
X766110Y125270
X761950Y126450
X779594Y126865
X772810Y179901
X772700Y183300
X769100Y187800
X765900Y191900
X768579Y203964
X764900Y207200
X761600Y207300
X771654Y209056
X762205Y212205
X771654
X768504Y215355
X771654
X762205
Y221654
X777953
X774804Y221655
X765354Y221654
X774804Y224804
X765355
Y227953
X777954
X774804Y227954
X777954Y231103
X765354Y231102
X765355Y234253
X765353Y237402
X777954
X771655
X762217Y240526
X765355Y240552
X768505Y243702
X765354Y246850
X762167
X768467
X771653Y246887
X762168Y253149
X768467
X771654Y253150
X765355
X777953Y256300
X768518Y259425
X771654Y259449
X762218Y259425
X765355Y259449
X777976Y259461
X777967Y262576
X771654Y265749
X765355
X774803
X777976Y265761
X762181Y265762
X768480
X774826Y268910
X765356Y272048
X762181Y272060
X762206Y275197
X774789Y275174
X765356Y275197
X777953Y275198
X762206Y278347
X765356
X777953
X777915Y281496
X765369Y281474
X771669
X762189Y281514
X768489Y281474
X771653Y287794
X777952
X762204
X774802
X765353
X768503
X762229Y290933
X762225Y297227
X771654Y297243
X769768Y304464
X777790Y304778
X769266Y326534
X766437Y329363
X763963Y331837
X761134Y334666
X777655Y335963
X775181Y338437
X772352Y341266
X768384Y345134
X765555Y347963
X763081Y350437
X760252Y353266
X777434Y353566
X768500Y480000
X774700Y483600
X777600Y512200
X771184Y514916
X763809Y537191
X782709Y537691
X795922Y531500
X797323Y512162
X781700Y510900
X782000Y505600
X794700Y505200
X780750Y496750
X781050Y492550
X790357Y377781
X795026Y374556
X799426Y374456
X780263Y350737
X782737Y348263
X785566Y345434
X789334Y341766
X799534Y339466
X792163Y338937
X794637Y336463
X797466Y333634
X780484Y333134
X780300Y309300
X796875Y304331
X790526Y300406
X793701Y300393
X793700Y297243
X787402
X781102Y297244
X796849Y297243
X793694Y290959
X790545
X796839Y290934
Y287784
X790550Y287795
X781100Y287800
X787400Y287795
X793703Y287797
X784251Y287794
X784221Y284652
X781120Y284665
X790551Y284646
X793675Y284637
X796862Y281522
X793679Y281508
X784249Y281464
X796868Y278364
X787419Y278354
X790551Y278384
X793675Y278357
X784243Y278318
X793737Y275196
X787438Y275197
X790519Y272053
X787426Y272060
X796832Y272064
X793682
X784290Y272047
X781064
X796850Y268910
X793683Y268879
X784252Y268885
X793674Y265758
X781080Y265763
X790538Y265723
X796822Y262588
X793699Y262634
X784258Y262618
X790551Y259486
X784267Y259426
X796822Y256289
X790523
X784267Y256276
X793700Y256262
X784277Y253162
X790550Y253150
X796821Y246859
X781127Y246863
X784277
X787402Y243701
X784277Y243713
X793672Y243709
X787402Y240552
X793672Y240560
X781103Y237402
X793701
Y234254
X781103Y231103
X793701
X784253
Y227953
X793701Y227954
X781103
X781102Y221654
X793701
X784252
X790551
X796850
X787402
X787401Y215354
X781300Y207800
X795593Y206063
X786388Y183429
X786343Y179959
X793957Y113436
X781250Y101750
X792600Y101300
X794650Y86050
X795832Y66750
X780815Y47062
X787360Y35650
X818785Y50692
X802786Y57150
X813349Y73142
X809349Y73197
X803000Y117100
X801340Y179597
X801385Y183067
X802246Y205826
X802227Y208424
X808400Y210800
X804600
X814262Y218950
X816900Y231700
X807468Y234464
X803158Y237414
X806918Y237804
X810688Y238944
X803129Y240535
X810277Y243190
X806862Y243302
X800021Y243717
X808923Y245979
X799991Y249972
X816079Y250464
X806968Y253464
X803150Y256336
X799972Y256309
X803160Y259454
X807177Y261023
X799972Y262588
X810079Y271264
X799974Y272058
X799999Y278345
X812164Y279674
X799999Y284645
X809968Y290464
X799999Y290944
X808400Y300900
X803300Y303700
X814450Y306950
X811600Y317300
X810300Y326450
X807666Y331334
X804837Y334163
X817514Y336325
X802363Y336637
X817700Y385700
X810946Y389734
X811112Y393735
X806400Y398700
X810100Y404934
X809384Y484984
X804584Y526584
X800800Y526900
X813150Y533450
X821050Y533350
X829500Y481500
X820343Y333496
X822817Y331022
X825646Y328193
X823250Y319350
X838581Y289419
X834581Y270619
X837409Y267791
X828781Y264119
X831609Y261291
X834791Y258109
X837619Y255281
X828117Y254500
X830945Y251672
X834127Y248490
X836955Y245662
X828000Y243100
X826000Y233400
X832148Y204444
X831504Y199129
X821962Y189277
X826925Y57425
X841300Y54200
X843419Y261781
X840591Y264609
X849419Y267581
X846591Y270409
X843409Y273591
X840581Y276419
X847419Y280581
X844591Y283409
X852919Y286081
X841409Y286591
X850091Y288909
X858919Y292081
X846909Y292091
X844081Y294919
X856091Y294909
X852909Y298091
X850081Y300919
X854419Y307581
X851591Y310409
X848409Y313591
X845581Y316419
X857581Y391433
X851100Y407500
X857000Y410600
X846000Y476100
X849050Y481050
X850950Y489300
X861000Y410500
X872750Y403400
X886540Y388996
X888668Y322100
X883240Y301973
X896969Y301500
X882871Y243771
X892449Y241249
X888551Y226649
X886300Y221150
T03
X464000Y35500
X468000Y31500
Y35400
Y39500
X472000Y35500
X601500Y363600
X625300Y539900
X625500Y536100
X629080Y539920
X629200Y536040
X805100Y504900
X805200Y499900
X805300Y494900
X810200
X810214Y499850
X810400Y505000
X815100Y499800
X815200Y505000
X815300Y494700
X709569Y582496
X709296Y572599
Y577599
X705969Y582496
X705696Y572599
X704796Y577599
X702369Y582496
X702096Y572599
X700546Y577599
X698769Y582496
X698496Y572599
X696296Y577599
X695169Y582496
X694896Y572599
X691796Y577599
X691569Y582496
X691296Y572599
X371400Y612700
Y606400
X371300Y618800
X365500Y619000
X365300Y606500
X365164Y612620
X358900Y618800
Y612800
X358800Y606300
X311386Y633450
X311186Y638550
X306300Y638600
X306286Y633650
X301386
X301286Y638650
X311286Y643750
X306486
X301186Y643650
X300720Y704920
X300620Y715220
X300520Y710020
X295820Y715220
X295634Y710070
X295620Y705120
X290720
X290620Y710120
X290520Y715120
X139916Y709422
Y705822
Y716622
Y713022
X135019Y706095
Y719095
Y710595
Y714845
X130019Y709695
Y706095
Y716895
Y713295
X70800Y660700
X70700Y671000
X70600Y665800
X65900Y671000
X65714Y665850
X65700Y660900
X60800
X60700Y665900
X60600Y670900
X130019Y724095
Y720495
X135019Y723595
X139916Y723822
Y720222
T04
X428740Y121654
Y125985
X421653Y126378
Y130709
X428740Y131496
Y135827
X421653Y136221
X428740Y140158
X421653Y140551
Y144882
X428740Y145670
Y150000
X421653Y150394
X428740Y154331
X421653Y154725
Y159055
X428740Y159843
Y164173
X421653Y164567
X428740Y168504
X421653Y168898
Y173229
X428740Y174016
X421653Y178740
Y183071
X435827
Y178740
Y173229
Y168898
Y164567
Y159055
Y154725
Y150394
Y144882
Y140551
Y136221
Y130709
Y126378
X442913Y121654
Y125985
Y131496
Y135827
Y140158
Y145670
Y150000
Y154331
Y159843
Y164173
Y168504
Y174016
X450000Y183071
Y178740
X457086Y174016
X450000Y173229
Y168898
X457086Y168504
X450000Y164567
X457086Y164173
Y159843
X450000Y159055
Y154725
X457086Y154331
X450000Y150394
X457086Y150000
Y145670
X450000Y144882
Y140551
X457086Y140158
X450000Y136221
X457086Y135827
Y131496
X450000Y130709
Y126378
X457086Y125985
Y121654
X464173Y126378
Y130709
Y136221
Y140551
Y144882
Y150394
Y154725
Y159055
Y164567
Y168898
Y173229
Y178740
Y183071
X471260Y174016
Y168504
Y164173
Y159843
Y154331
Y150000
Y145670
Y140158
Y135827
Y131496
Y125985
Y121654
X506693Y126378
Y130709
Y136221
Y140551
Y144882
Y150394
Y154725
Y159055
Y164567
Y168898
Y173229
Y178740
Y183071
X513779Y174016
Y168504
Y164173
Y159843
Y154331
Y150000
Y145670
Y140158
Y135827
Y131496
Y125985
Y121654
X527953
Y125985
X520866Y126378
Y130709
X527953Y131496
Y135827
X520866Y136221
X527953Y140158
X520866Y140551
Y144882
X527953Y145670
Y150000
X520866Y150394
X527953Y154331
X520866Y154725
Y159055
X527953Y159843
Y164173
X520866Y164567
X527953Y168504
X520866Y168898
Y173229
X527953Y174016
X520866Y178740
Y183071
X535039
Y178740
Y173229
Y168898
Y164567
Y159055
Y154725
Y150394
Y144882
Y140551
Y136221
Y130709
Y126378
X542126Y121654
Y125985
X549212Y126378
Y130709
X542126Y131496
Y135827
X549212Y136221
X542126Y140158
X549212Y140551
Y144882
X542126Y145670
Y150000
X549212Y150394
X542126Y154331
X549212Y154725
Y159055
X542126Y159843
Y164173
X549212Y164567
X542126Y168504
X549212Y168898
Y173229
X542126Y174016
X549212Y178740
Y183071
X556299Y174016
Y168504
Y164173
Y159843
Y154331
Y150000
Y145670
Y140158
Y135827
Y131496
Y125985
Y121654
T05
X618110Y120079
Y105118
Y90157
Y75197
X621063Y69685
X629921
X624015Y72441
X626969Y75197
X629921Y84646
X621063
X624015Y87402
X626969Y90157
X621063Y99606
X629921
X624015Y102362
X626969Y105118
X629921Y114567
X621063
X624015Y117323
X626969Y120079
X635827
X632873Y117323
X638780Y114567
X635827Y105118
X632873Y102362
X638780Y99606
X635827Y90157
X632873Y87402
X638780Y84646
X635827Y75197
X632873Y72441
X638780Y69685
X641732Y72441
Y87402
Y102362
Y117323
X696850Y120079
X699803Y114567
X696850Y105118
X699803Y99606
X696850Y90157
X699803Y84646
X696850Y75197
X699803Y69685
X708661
X702755Y72441
X705709Y75197
X708661Y84646
X702755Y87402
X705709Y90157
X708661Y99606
X702755Y102362
X705709Y105118
X708661Y114567
X702755Y117323
X705709Y120079
X714567
X711613Y117323
X717520Y114567
X714567Y105118
X711613Y102362
X717520Y99606
X714567Y90157
X711613Y87402
X717520Y84646
X714567Y75197
X711613Y72441
X717520Y69685
X720472Y72441
Y87402
Y102362
Y117323
T06
X18721Y8500
X23721
X28721
X33721
X38721
X43721
X58721
X13721
X53721
X48721
X8500Y13279
Y18279
Y23279
Y28279
Y33279
Y38279
Y43279
Y48279
Y53279
Y58279
Y63279
Y68279
Y73279
Y78279
Y83279
Y88279
Y93279
Y98279
Y103279
Y108279
Y113279
Y118279
Y123279
Y128279
Y133279
Y138279
Y143279
Y148279
Y153279
Y158279
Y163279
Y168279
Y173279
Y178279
Y183279
Y188279
Y193279
Y198279
Y203279
Y208279
Y213279
Y218279
Y223279
Y228279
Y233279
Y238279
Y243279
Y248279
Y253279
Y258279
Y263279
Y268279
Y273279
Y278279
Y283279
Y288279
Y293279
Y298279
Y303279
Y308279
Y313279
Y318279
Y323279
Y328279
Y333279
Y338279
Y343279
Y348279
Y353279
Y358279
Y363279
Y368279
Y373279
Y378279
Y383279
Y388279
Y393279
Y398279
Y403279
Y408279
Y413279
Y418279
Y423279
Y428279
Y433279
Y438279
Y443279
Y448279
Y453279
Y458279
Y463279
Y468279
Y473279
Y478279
Y483279
Y488279
Y493279
Y498279
Y503279
Y508279
Y513279
Y518279
Y523279
Y528279
Y533279
Y538279
Y543279
Y548279
Y553279
Y558279
Y563279
Y568279
Y573279
Y578279
Y583279
Y588279
Y593279
Y598279
Y603279
Y608279
Y613279
Y618279
Y623279
Y628279
Y633279
Y638279
Y643279
Y648279
Y653279
Y658279
Y663279
Y668279
Y673279
Y678279
Y683279
Y688279
Y693279
Y698279
Y703279
Y708279
Y713279
Y718279
X8892Y723187
X11090Y727806
X13500Y732400
X15800Y736900
X18100Y741500
X20300Y746200
X22600Y750800
X33100Y755600
X28100
X114057Y755280
X74057
X69057
X99057
X109057
X89057
X79057
X94057
X119057
X104057
X84057
X96500Y744800
X115700
X106100
X101300
X110900
X91700
X78370Y724300
X83170
X78370Y719500
X83170
X86600Y708300
X86500Y703100
X99600Y683500
X81300Y680100
X75300Y679300
X99600Y678500
X81300Y675100
X75300Y674300
X99600Y673500
X85400Y667100
X90200
X96800Y662000
X103500Y650535
Y645500
X103600Y637800
X75534Y625175
X80334
X112197Y425406
Y420406
Y415406
Y410406
Y405406
Y400406
Y395406
Y390406
Y385406
Y380406
Y375406
Y370406
Y365406
Y360406
Y355406
Y350406
Y345406
Y340406
Y335406
Y330406
Y325406
Y320406
Y315406
Y310406
Y305406
Y300406
Y295406
Y290406
Y285406
Y280406
Y275406
Y270406
Y265406
Y260406
Y255406
Y250406
Y245406
Y240406
Y235406
Y230406
Y225406
Y220406
Y215406
Y210406
Y205406
Y200406
Y195406
Y190406
Y185406
Y180406
Y175406
Y170406
Y165406
Y160406
Y155406
Y150406
Y145406
Y120406
Y115406
Y110406
Y105406
Y100406
Y95406
Y90406
Y85406
Y80406
Y75406
Y70406
Y65406
Y60406
Y55406
X98721Y8500
X63721
X103721
X68721
X73721
X78721
X83721
X88721
X93721
X108721
X122435Y661982
Y666782
X134223Y691027
X155400Y717700
X125300Y744800
X120500
X174057Y755280
X159057
X164057
X144057
X139057
X154057
X134057
X149057
X129057
X169057
X124057
X179057
X194057
X209057
X189057
X184057
X229057
X199057
X239057
X219057
X214057
X204057
X234057
X224057
X208300Y704985
X222700
X198700
X193900
X217900
X203500
X213100
X279057Y755280
X294057
X289057
X284057
X269057
X254057
X249057
X299057
X259057
X244057
X274057
X264057
X249500Y738700
Y733900
Y729100
Y724300
Y719500
X299350Y674700
X296282Y189224
Y184424
X296020Y29420
Y24420
Y19420
Y14420
Y9420
X300120Y8500
X305120
X315120
X310120
X301082Y184424
Y189224
X335132Y195874
X321382Y197574
Y202374
X335132Y205974
X305862Y210014
X334882Y215874
Y220874
X335300Y609800
X335000Y615400
Y621200
X325600Y640100
X330400
X335200
X308186Y653754
X312986
X322586
X317786
X304150Y674700
X335350Y684650
X334650Y689700
X330200Y709300
X325700Y711600
X320320Y711720
X315520
X305500Y721000
X310500
X305500Y726000
X310500
X304057Y755280
X319057
X344057
X334057
X309057
X339057
X329057
X314057
X324057
X381638
X384809Y752321
X387045Y747849
X389281Y743376
X391517Y738904
X393753Y734432
X395989Y729960
X398225Y725488
X515915Y80576
X508668Y79607
X503550Y79500
X531664Y78463
X536794Y77373
X520310Y76700
X506100Y75060
X511100
X516628Y71806
X525200Y71440
X511100Y70060
X520585Y68348
X515200Y66440
X520000Y63400
X526434Y43701
X516834
X521634
X516834Y38901
X521634
X516834Y34101
X521634
X595700Y29800
X595500Y35600
X581312Y364825
X576512
Y369625
X581312
X576610Y388416
Y393416
Y398416
Y403416
Y408416
Y413416
Y418416
Y423416
Y428416
Y433416
Y438416
Y443416
Y448416
Y453416
Y458416
Y463416
Y468416
Y473416
Y478416
Y483416
Y488416
Y493416
Y498416
Y503416
Y508416
Y513416
Y518416
Y523416
Y528416
Y533416
Y538416
Y543416
Y548416
Y553416
Y558416
Y563416
Y568416
Y573416
Y578416
Y583416
Y588416
Y593416
Y598416
Y603416
Y608416
Y613416
Y618416
Y623416
Y628416
Y633416
Y638416
Y643416
Y648416
Y653416
Y658416
Y663416
Y668416
Y673416
Y678416
Y683416
Y688416
Y693416
Y698416
Y703416
Y708416
Y713416
Y718416
X577063Y723309
X579299Y727781
X581535Y732253
X583771Y736725
X586007Y741198
X588243Y745670
X590479Y750142
X592715Y754614
X639722Y755280
X634722
X644722
X649722
X659722
X654722
X655000Y705000
Y700200
Y695400
Y690600
Y685800
X645300Y684000
Y679200
Y674400
Y669600
Y664800
Y660000
Y655200
Y650400
Y645600
Y640800
X656887Y560010
X657000Y555000
X616710Y534500
X615500Y529800
X645200Y521900
X650400Y517600
X656400Y517500
X621600Y486619
X626958Y486419
X609000Y483500
X635000Y482500
X629500
X609000Y478500
X629500Y477000
X635000Y476500
X609000Y473500
X629500Y471500
X635000Y471000
X610000Y467500
X642500Y464700
X642600Y459500
X642700Y454400
X642500Y449100
X658000Y431500
Y426000
Y420500
Y414000
Y409000
X609200Y330400
X600700Y35700
X600900Y29700
X708483Y311988
X713283
X718940Y326270
X706700Y413900
X710200Y417400
X698700Y417600
X671000Y421000
X676000
X710200Y422900
X698700Y423100
X676000Y426000
X671000
X710200Y427900
X698700Y428100
X671000Y431000
X676000
X714900Y453600
X715200Y459600
Y465000
X661500Y517600
X689500Y518500
X694690Y519034
X694738Y523940
X689500Y524000
X670400Y536700
Y541500
Y546300
Y551100
X662000Y555000
X670400Y555900
X661887Y560010
X670400Y560700
Y565500
X687015Y643700
Y648500
Y653300
Y658100
Y662900
Y667700
Y672500
Y677300
Y682100
X673950Y686104
Y691104
Y696104
Y701104
Y706104
X694722Y755280
X689722
X719722
X679722
X714722
X709722
X664722
X704722
X674722
X699722
X684722
X669722
X774722
X744722
X754722
X724722
X749722
X739722
X769722
X729722
X759722
X779722
X764722
X734722
X735484Y467778
Y462978
Y458178
X776200Y458000
X735484Y453378
Y448578
X740300Y446300
X735484Y443778
X740300Y441500
X735484Y438978
X740300Y436700
X774200Y436000
X779000
X735484Y434178
X740300Y431900
X735484Y429378
X759600Y427100
X750000
X774000
X754800
X740300
X778800
X764400
X769200
X765500Y405400
X751100
X775100
X779900
X755900
X760700
X770300
X723900Y326350
X754000Y177500
Y172700
X765100Y8500
X760100
X745100
X770100
X755100
X750100
X775100
X787895
X832895
X802895
X807895
X837895
X812895
X780100
X827895
X822895
X817895
X792895
X797895
X826900Y332500
X825300Y339900
X825100Y347300
X798359Y351659
X828100Y352900
X795193Y355540
X821502Y358356
X826993Y358840
X791786Y359001
X821653Y363488
X827145Y363638
X814592Y374322
X809792
Y379122
X814592
X789500Y405400
X784700
X788400Y427100
X783600
X793400Y436000
X788600
X783800
X813900Y436500
X809100
X804300
X823500
X818700
X790600Y458000
X781000
X785800
X798000Y459300
X832800
X828000
X823200
X818400
X812400
X807600
X802800
X839700Y501500
X834900
X830100
X832000Y516000
X827000
Y521000
X832000
X829722Y755280
X834722
X814722
X809722
X794722
X804722
X819722
X839722
X824722
X799722
X784722
X789722
X844722
X894722
X854722
X849722
X848700Y470600
Y465200
X843900Y464000
X880887Y399474
X874727Y398458
X864727
X869727
X881147Y394517
X840800Y352800
X842900Y347200
X842600Y339400
X841100Y332300
X842895Y8500
X862895
X872895
X877895
X867895
X882895
X887895
X857895
X892895
X852895
X897895
X847895
X907895
X912895
X902895
X916697Y14698
Y19698
Y24698
Y29698
Y34698
Y39698
Y44698
Y49698
Y54698
Y59698
Y64698
Y69698
Y74698
Y79698
Y84698
Y89698
Y94698
Y99698
Y104698
Y109698
Y114698
Y119698
Y124698
Y129698
Y134698
Y139698
Y144698
Y149698
Y154698
Y159698
Y164698
Y169698
Y174698
Y179698
Y184698
Y189698
Y194698
Y199698
Y204698
Y209698
Y214698
Y219698
Y224698
Y229698
Y234698
Y239698
Y244698
Y249698
Y254698
Y259698
Y264698
Y269698
Y274698
Y279698
Y284698
Y289698
Y294698
Y299698
Y304698
Y309698
Y314698
Y319698
Y324698
Y329698
Y334698
Y339698
Y344698
Y349698
Y354698
Y359698
Y364698
Y369698
Y374698
Y379698
Y384698
Y389698
Y394698
Y399698
Y404698
Y409698
Y414698
Y419698
Y424698
Y429698
Y434698
Y439698
Y444698
Y449698
Y454698
Y459698
Y464698
Y469698
Y474698
Y479698
Y484698
Y489698
Y494698
Y499698
Y504698
Y509698
Y514698
Y519698
Y524698
Y529698
Y534698
Y539698
Y544698
Y549698
Y554698
Y559698
Y564698
Y569698
Y574698
Y579698
Y584698
Y589698
Y594698
Y599698
Y604698
Y609698
Y614698
Y619698
Y624698
Y629698
Y634698
Y639698
Y644698
Y649698
Y654698
Y659698
Y664698
Y669698
Y674698
Y679698
Y684698
Y689698
Y694698
Y699698
Y704698
Y709698
Y714698
Y719698
X914700Y726100
X912436Y730603
X910200Y735300
X907564Y739747
X905500Y744400
X903192Y748791
X900800Y753700
T07
X608267Y20039
X651575
X687007
X730315
Y72441
X687007
X651575
X608267
X624015Y126811
X641732
X702755
X720472
T08
X346457Y57007
X353543Y55039
Y62913
X346457Y66850
X353543Y70787
Y78661
X346457Y74724
Y84567
X353543Y86535
T09
X564803Y24409
X574803
X584803
X753780
X763780
X773780
X801024
X811024
X821024
T10
X33464Y34449
X38386Y24606
X56102
X61024Y34449
X80708Y44292
X85630Y34449
X103346
X108268Y44292
X590300Y574400
X600300
X610300
T11
X629921Y57874
X708661
T12
X405511Y39370
X70865Y98425
Y472440
X314960
X612204Y433070
X875984
Y740157
X612204
X364173
T13
X875985Y59055
X49213Y740157
T14
X163189Y669291
T15
X201801Y684252
X225601
T16
X305906Y388386
T17
X305906Y182874
T18
X18700Y54650
X209189Y37075
Y383483
X489331Y245605
Y698924
X902500Y676000
X901000Y21400
T19
X488838Y164744
T20
X488838Y137225
T21
X652756Y180000
X865353Y332598
T22
X309055Y157677
X90157Y413583
M30
